(kicad_pcb
	(version 20260206)
	(generator "pcbnew")
	(generator_version "10.0")
	(general
		(thickness 1.6)
		(legacy_teardrops no)
	)
	(paper "A4")
	(title_block
		(title "03242023_DA0F0TMBIJ0_F0T_Motherboard_J_brd_V01_OCP.brd")
		(comment 1 "Grand Teton / footprints 1930-1935 of 6105")
	)
	(layers
		(0 "F.Cu" signal "TOP")
		(4 "In1.Cu" signal "GND")
		(6 "In2.Cu" signal "IN1")
		(8 "In3.Cu" signal "GND1")
		(10 "In4.Cu" signal "IN2")
		(12 "In5.Cu" signal "GND2")
		(14 "In6.Cu" signal "IN3")
		(16 "In7.Cu" signal "GND3")
		(18 "In8.Cu" signal "VCC")
		(20 "In9.Cu" signal "VCC1")
		(22 "In10.Cu" signal "GND4")
		(24 "In11.Cu" signal "IN4")
		(26 "In12.Cu" signal "GND5")
		(28 "In13.Cu" signal "IN5")
		(30 "In14.Cu" signal "GND6")
		(32 "In15.Cu" signal "IN6")
		(34 "In16.Cu" signal "GND7")
		(2 "B.Cu" signal "BOTTOM")
		(9 "F.Adhes" user "F.Adhesive")
		(11 "B.Adhes" user "B.Adhesive")
		(13 "F.Paste" user "Package Geometry/Pastemask Top")
		(15 "B.Paste" user "Package Geometry/Pastemask Bottom")
		(5 "F.SilkS" user "Ref Des/Silkscreen Top")
		(7 "B.SilkS" user "Ref Des/Silkscreen Bottom")
		(1 "F.Mask" user "Board Geometry/Soldermask Top")
		(3 "B.Mask" user "Board Geometry/Soldermask Bottom")
		(17 "Dwgs.User" user "User.Drawings")
		(19 "Cmts.User" user "User.Comments")
		(21 "Eco1.User" user "User.Eco1")
		(23 "Eco2.User" user "User.Eco2")
		(25 "Edge.Cuts" user "Board Geometry/Outline")
		(27 "Margin" user)
		(31 "F.CrtYd" user "Package Geometry/Place Bound Top")
		(29 "B.CrtYd" user "Package Geometry/Place Bound Bottom")
		(35 "F.Fab" user "Ref Des/Assembly Top")
		(33 "B.Fab" user "Ref Des/Assembly Bottom")
	)
	(footprint ""
		(layer "F.Cu")
		(at 99.388422 -414.776666 -90)
		(property "Reference" "R4203"
			(at 0 0 270)
			(layer "F.SilkS")
			(hide yes)
			(effects
				(font
					(size 1.27 1.27)
				)
			)
		)
		(property "Value" ""
			(at 0 0 270)
			(layer "F.Fab")
			(effects
				(font
					(size 1.27 1.27)
				)
			)
		)
		(duplicate_pad_numbers_are_jumpers no)
		(fp_line
			(start -0.7874 0.4064)
			(end -0.7874 -0.4064)
			(stroke
				(width 0.1524)
				(type default)
			)
			(layer "F.SilkS")
		)
		(fp_line
			(start 0.7874 0.4064)
			(end -0.7874 0.4064)
			(stroke
				(width 0.1524)
				(type default)
			)
			(layer "F.SilkS")
		)
		(fp_line
			(start -0.7874 -0.4064)
			(end 0.7874 -0.4064)
			(stroke
				(width 0.1524)
				(type default)
			)
			(layer "F.SilkS")
		)
		(fp_line
			(start 0.7874 -0.4064)
			(end 0.7874 0.4064)
			(stroke
				(width 0.1524)
				(type default)
			)
			(layer "F.SilkS")
		)
		(fp_line
			(start -0.67945 0.3048)
			(end -0.67945 -0.305054)
			(stroke
				(width 0.1)
				(type default)
			)
			(layer "F.Fab")
		)
		(fp_line
			(start -0.12065 0.3048)
			(end -0.67945 0.3048)
			(stroke
				(width 0.1)
				(type default)
			)
			(layer "F.Fab")
		)
		(fp_line
			(start 0.120396 0.3048)
			(end 0.120396 0.2794)
			(stroke
				(width 0.1)
				(type default)
			)
			(layer "F.Fab")
		)
		(fp_line
			(start 0.67945 0.3048)
			(end 0.120396 0.3048)
			(stroke
				(width 0.1)
				(type default)
			)
			(layer "F.Fab")
		)
		(fp_line
			(start -0.12065 0.2794)
			(end -0.12065 0.3048)
			(stroke
				(width 0.1)
				(type default)
			)
			(layer "F.Fab")
		)
		(fp_line
			(start 0.120396 0.2794)
			(end -0.12065 0.2794)
			(stroke
				(width 0.1)
				(type default)
			)
			(layer "F.Fab")
		)
		(fp_line
			(start -0.12065 -0.2794)
			(end 0.12065 -0.2794)
			(stroke
				(width 0.1)
				(type default)
			)
			(layer "F.Fab")
		)
		(fp_line
			(start 0.12065 -0.2794)
			(end 0.12065 -0.3048)
			(stroke
				(width 0.1)
				(type default)
			)
			(layer "F.Fab")
		)
		(fp_line
			(start 0.12065 -0.3048)
			(end 0.67945 -0.3048)
			(stroke
				(width 0.1)
				(type default)
			)
			(layer "F.Fab")
		)
		(fp_line
			(start 0.67945 -0.3048)
			(end 0.67945 0.3048)
			(stroke
				(width 0.1)
				(type default)
			)
			(layer "F.Fab")
		)
		(fp_line
			(start -0.67945 -0.305054)
			(end -0.12065 -0.305054)
			(stroke
				(width 0.1)
				(type default)
			)
			(layer "F.Fab")
		)
		(fp_line
			(start -0.12065 -0.305054)
			(end -0.12065 -0.2794)
			(stroke
				(width 0.1)
				(type default)
			)
			(layer "F.Fab")
		)
		(pad "1" smd circle
			(at -0.40005 0 270)
			(size 0 0)
			(layers "F.Cu" "F.Mask" "F.Paste")
			(net "U272_2_ADD0")
		)
		(pad "2" smd circle
			(at 0.40005 0 270)
			(size 0 0)
			(layers "F.Cu" "F.Mask" "F.Paste")
			(net "GND")
		)
	)
	(footprint ""
		(layer "F.Cu")
		(at 372.74373 -408.517344 -90)
		(property "Reference" "C870"
			(at 0 0 270)
			(layer "F.SilkS")
			(hide yes)
			(effects
				(font
					(size 1.27 1.27)
				)
			)
		)
		(property "Value" ""
			(at 0 0 270)
			(layer "F.Fab")
			(effects
				(font
					(size 1.27 1.27)
				)
			)
		)
		(duplicate_pad_numbers_are_jumpers no)
		(fp_line
			(start -0.299974 0.150114)
			(end -0.299974 -0.150114)
			(stroke
				(width 0.1)
				(type default)
			)
			(layer "F.Fab")
		)
		(fp_line
			(start 0.299974 0.150114)
			(end -0.299974 0.150114)
			(stroke
				(width 0.1)
				(type default)
			)
			(layer "F.Fab")
		)
		(fp_line
			(start -0.299974 -0.150114)
			(end 0.299974 -0.150114)
			(stroke
				(width 0.1)
				(type default)
			)
			(layer "F.Fab")
		)
		(fp_line
			(start 0.299974 -0.150114)
			(end 0.299974 0.150114)
			(stroke
				(width 0.1)
				(type default)
			)
			(layer "F.Fab")
		)
		(pad "1" smd rect
			(at -0.2667 0 270)
			(size 0.3048 0.381)
			(layers "F.Cu" "F.Mask" "F.Paste")
			(net "P5E_CPU0_PE3_TX_C_DN<15>")
		)
		(pad "2" smd rect
			(at 0.2667 0 270)
			(size 0.3048 0.381)
			(layers "F.Cu" "F.Mask" "F.Paste")
			(net "P5E_CPU0_PE3_TX_DN<15>")
		)
	)
	(footprint ""
		(layer "F.Cu")
		(at 109.744002 -333.525368 -90)
		(property "Reference" "PC526_P1_3"
			(at 0 0 270)
			(layer "F.SilkS")
			(hide yes)
			(effects
				(font
					(size 1.27 1.27)
				)
			)
		)
		(property "Value" ""
			(at 0 0 270)
			(layer "F.Fab")
			(effects
				(font
					(size 1.27 1.27)
				)
			)
		)
		(duplicate_pad_numbers_are_jumpers no)
		(fp_line
			(start -0.7874 0.4064)
			(end -0.7874 -0.4064)
			(stroke
				(width 0.1524)
				(type default)
			)
			(layer "F.SilkS")
		)
		(fp_line
			(start 0.7874 0.4064)
			(end -0.7874 0.4064)
			(stroke
				(width 0.1524)
				(type default)
			)
			(layer "F.SilkS")
		)
		(fp_line
			(start -0.7874 -0.4064)
			(end 0.7874 -0.4064)
			(stroke
				(width 0.1524)
				(type default)
			)
			(layer "F.SilkS")
		)
		(fp_line
			(start 0.7874 -0.4064)
			(end 0.7874 0.4064)
			(stroke
				(width 0.1524)
				(type default)
			)
			(layer "F.SilkS")
		)
		(fp_line
			(start -0.67945 0.3048)
			(end -0.67945 -0.305054)
			(stroke
				(width 0.1)
				(type default)
			)
			(layer "F.Fab")
		)
		(fp_line
			(start -0.12065 0.3048)
			(end -0.67945 0.3048)
			(stroke
				(width 0.1)
				(type default)
			)
			(layer "F.Fab")
		)
		(fp_line
			(start 0.120396 0.3048)
			(end 0.120396 0.2794)
			(stroke
				(width 0.1)
				(type default)
			)
			(layer "F.Fab")
		)
		(fp_line
			(start 0.67945 0.3048)
			(end 0.120396 0.3048)
			(stroke
				(width 0.1)
				(type default)
			)
			(layer "F.Fab")
		)
		(fp_line
			(start -0.12065 0.2794)
			(end -0.12065 0.3048)
			(stroke
				(width 0.1)
				(type default)
			)
			(layer "F.Fab")
		)
		(fp_line
			(start 0.120396 0.2794)
			(end -0.12065 0.2794)
			(stroke
				(width 0.1)
				(type default)
			)
			(layer "F.Fab")
		)
		(fp_line
			(start -0.12065 -0.2794)
			(end 0.12065 -0.2794)
			(stroke
				(width 0.1)
				(type default)
			)
			(layer "F.Fab")
		)
		(fp_line
			(start 0.12065 -0.2794)
			(end 0.12065 -0.3048)
			(stroke
				(width 0.1)
				(type default)
			)
			(layer "F.Fab")
		)
		(fp_line
			(start 0.12065 -0.3048)
			(end 0.67945 -0.3048)
			(stroke
				(width 0.1)
				(type default)
			)
			(layer "F.Fab")
		)
		(fp_line
			(start 0.67945 -0.3048)
			(end 0.67945 0.3048)
			(stroke
				(width 0.1)
				(type default)
			)
			(layer "F.Fab")
		)
		(fp_line
			(start -0.67945 -0.305054)
			(end -0.12065 -0.305054)
			(stroke
				(width 0.1)
				(type default)
			)
			(layer "F.Fab")
		)
		(fp_line
			(start -0.12065 -0.305054)
			(end -0.12065 -0.2794)
			(stroke
				(width 0.1)
				(type default)
			)
			(layer "F.Fab")
		)
		(pad "1" smd circle
			(at -0.40005 0 270)
			(size 0 0)
			(layers "F.Cu" "F.Mask" "F.Paste")
			(net "PVCCIN_CPU1_PVCC")
		)
		(pad "2" smd circle
			(at 0.40005 0 270)
			(size 0 0)
			(layers "F.Cu" "F.Mask" "F.Paste")
			(net "GND")
		)
	)
	(footprint ""
		(layer "F.Cu")
		(at 49.755552 -146.550634 90)
		(property "Reference" "PR1727"
			(at 0 0 90)
			(layer "F.SilkS")
			(hide yes)
			(effects
				(font
					(size 1.27 1.27)
				)
			)
		)
		(property "Value" ""
			(at 0 0 90)
			(layer "F.Fab")
			(effects
				(font
					(size 1.27 1.27)
				)
			)
		)
		(duplicate_pad_numbers_are_jumpers no)
		(fp_line
			(start 0.7874 -0.4064)
			(end 0.7874 0.4064)
			(stroke
				(width 0.1524)
				(type default)
			)
			(layer "F.SilkS")
		)
		(fp_line
			(start -0.7874 -0.4064)
			(end 0.7874 -0.4064)
			(stroke
				(width 0.1524)
				(type default)
			)
			(layer "F.SilkS")
		)
		(fp_line
			(start 0.7874 0.4064)
			(end -0.7874 0.4064)
			(stroke
				(width 0.1524)
				(type default)
			)
			(layer "F.SilkS")
		)
		(fp_line
			(start -0.7874 0.4064)
			(end -0.7874 -0.4064)
			(stroke
				(width 0.1524)
				(type default)
			)
			(layer "F.SilkS")
		)
		(fp_line
			(start -0.12065 -0.305054)
			(end -0.12065 -0.2794)
			(stroke
				(width 0.1)
				(type default)
			)
			(layer "F.Fab")
		)
		(fp_line
			(start -0.67945 -0.305054)
			(end -0.12065 -0.305054)
			(stroke
				(width 0.1)
				(type default)
			)
			(layer "F.Fab")
		)
		(fp_line
			(start 0.67945 -0.3048)
			(end 0.67945 0.3048)
			(stroke
				(width 0.1)
				(type default)
			)
			(layer "F.Fab")
		)
		(fp_line
			(start 0.12065 -0.3048)
			(end 0.67945 -0.3048)
			(stroke
				(width 0.1)
				(type default)
			)
			(layer "F.Fab")
		)
		(fp_line
			(start 0.12065 -0.2794)
			(end 0.12065 -0.3048)
			(stroke
				(width 0.1)
				(type default)
			)
			(layer "F.Fab")
		)
		(fp_line
			(start -0.12065 -0.2794)
			(end 0.12065 -0.2794)
			(stroke
				(width 0.1)
				(type default)
			)
			(layer "F.Fab")
		)
		(fp_line
			(start 0.120396 0.2794)
			(end -0.12065 0.2794)
			(stroke
				(width 0.1)
				(type default)
			)
			(layer "F.Fab")
		)
		(fp_line
			(start -0.12065 0.2794)
			(end -0.12065 0.3048)
			(stroke
				(width 0.1)
				(type default)
			)
			(layer "F.Fab")
		)
		(fp_line
			(start 0.67945 0.3048)
			(end 0.120396 0.3048)
			(stroke
				(width 0.1)
				(type default)
			)
			(layer "F.Fab")
		)
		(fp_line
			(start 0.120396 0.3048)
			(end 0.120396 0.2794)
			(stroke
				(width 0.1)
				(type default)
			)
			(layer "F.Fab")
		)
		(fp_line
			(start -0.12065 0.3048)
			(end -0.67945 0.3048)
			(stroke
				(width 0.1)
				(type default)
			)
			(layer "F.Fab")
		)
		(fp_line
			(start -0.67945 0.3048)
			(end -0.67945 -0.305054)
			(stroke
				(width 0.1)
				(type default)
			)
			(layer "F.Fab")
		)
		(pad "1" smd circle
			(at -0.40005 0 90)
			(size 0 0)
			(layers "F.Cu" "F.Mask" "F.Paste")
			(net "PVCCINFAON_CPU1_LSET2")
		)
		(pad "2" smd circle
			(at 0.40005 0 90)
			(size 0 0)
			(layers "F.Cu" "F.Mask" "F.Paste")
			(net "GND")
		)
	)
	(footprint ""
		(layer "F.Cu")
		(at 122.809 -60.035948 -90)
		(property "Reference" "R4624"
			(at 0 0 270)
			(layer "F.SilkS")
			(hide yes)
			(effects
				(font
					(size 1.27 1.27)
				)
			)
		)
		(property "Value" ""
			(at 0 0 270)
			(layer "F.Fab")
			(effects
				(font
					(size 1.27 1.27)
				)
			)
		)
		(duplicate_pad_numbers_are_jumpers no)
		(fp_line
			(start -0.7874 0.4064)
			(end -0.7874 -0.4064)
			(stroke
				(width 0.1524)
				(type default)
			)
			(layer "F.SilkS")
		)
		(fp_line
			(start 0.7874 0.4064)
			(end -0.7874 0.4064)
			(stroke
				(width 0.1524)
				(type default)
			)
			(layer "F.SilkS")
		)
		(fp_line
			(start -0.7874 -0.4064)
			(end 0.7874 -0.4064)
			(stroke
				(width 0.1524)
				(type default)
			)
			(layer "F.SilkS")
		)
		(fp_line
			(start 0.7874 -0.4064)
			(end 0.7874 0.4064)
			(stroke
				(width 0.1524)
				(type default)
			)
			(layer "F.SilkS")
		)
		(fp_line
			(start -0.67945 0.3048)
			(end -0.67945 -0.305054)
			(stroke
				(width 0.1)
				(type default)
			)
			(layer "F.Fab")
		)
		(fp_line
			(start -0.12065 0.3048)
			(end -0.67945 0.3048)
			(stroke
				(width 0.1)
				(type default)
			)
			(layer "F.Fab")
		)
		(fp_line
			(start 0.120396 0.3048)
			(end 0.120396 0.2794)
			(stroke
				(width 0.1)
				(type default)
			)
			(layer "F.Fab")
		)
		(fp_line
			(start 0.67945 0.3048)
			(end 0.120396 0.3048)
			(stroke
				(width 0.1)
				(type default)
			)
			(layer "F.Fab")
		)
		(fp_line
			(start -0.12065 0.2794)
			(end -0.12065 0.3048)
			(stroke
				(width 0.1)
				(type default)
			)
			(layer "F.Fab")
		)
		(fp_line
			(start 0.120396 0.2794)
			(end -0.12065 0.2794)
			(stroke
				(width 0.1)
				(type default)
			)
			(layer "F.Fab")
		)
		(fp_line
			(start -0.12065 -0.2794)
			(end 0.12065 -0.2794)
			(stroke
				(width 0.1)
				(type default)
			)
			(layer "F.Fab")
		)
		(fp_line
			(start 0.12065 -0.2794)
			(end 0.12065 -0.3048)
			(stroke
				(width 0.1)
				(type default)
			)
			(layer "F.Fab")
		)
		(fp_line
			(start 0.12065 -0.3048)
			(end 0.67945 -0.3048)
			(stroke
				(width 0.1)
				(type default)
			)
			(layer "F.Fab")
		)
		(fp_line
			(start 0.67945 -0.3048)
			(end 0.67945 0.3048)
			(stroke
				(width 0.1)
				(type default)
			)
			(layer "F.Fab")
		)
		(fp_line
			(start -0.67945 -0.305054)
			(end -0.12065 -0.305054)
			(stroke
				(width 0.1)
				(type default)
			)
			(layer "F.Fab")
		)
		(fp_line
			(start -0.12065 -0.305054)
			(end -0.12065 -0.2794)
			(stroke
				(width 0.1)
				(type default)
			)
			(layer "F.Fab")
		)
		(pad "1" smd circle
			(at -0.40005 0 270)
			(size 0 0)
			(layers "F.Cu" "F.Mask" "F.Paste")
			(net "JTAG_BMC_SW_OE")
		)
		(pad "2" smd circle
			(at 0.40005 0 270)
			(size 0 0)
			(layers "F.Cu" "F.Mask" "F.Paste")
			(net "JTAG_BMC_SW_R_OE")
		)
	)
	(footprint ""
		(layer "F.Cu")
		(at 384.359912 -76.14412 180)
		(property "Reference" "PU74"
			(at -2.749042 -2.999232 0)
			(unlocked yes)
			(layer "F.SilkS")
			(effects
				(font
					(size 0.7874 0.5842)
					(thickness 0.1524)
				)
				(justify left)
			)
		)
		(property "Value" ""
			(at 0 0 180)
			(layer "F.Fab")
			(effects
				(font
					(size 1.27 1.27)
				)
			)
		)
		(duplicate_pad_numbers_are_jumpers no)
		(fp_line
			(start 1.050036 1.549908)
			(end 1.050036 0.762)
			(stroke
				(width 0.1524)
				(type default)
			)
			(layer "F.SilkS")
		)
		(fp_line
			(start 1.050036 -0.762)
			(end 1.050036 -1.549908)
			(stroke
				(width 0.1524)
				(type default)
			)
			(layer "F.SilkS")
		)
		(fp_line
			(start 1.050036 -1.549908)
			(end 1.016 -1.549908)
			(stroke
				(width 0.1524)
				(type default)
			)
			(layer "F.SilkS")
		)
		(fp_line
			(start 1.016 1.549908)
			(end 1.050036 1.549908)
			(stroke
				(width 0.1524)
				(type default)
			)
			(layer "F.SilkS")
		)
		(fp_line
			(start -1.016 -1.549908)
			(end -1.050036 -1.549908)
			(stroke
				(width 0.1524)
				(type default)
			)
			(layer "F.SilkS")
		)
		(fp_line
			(start -1.050036 1.549908)
			(end -1.016 1.549908)
			(stroke
				(width 0.1524)
				(type default)
			)
			(layer "F.SilkS")
		)
		(fp_line
			(start -1.050036 0.762)
			(end -1.050036 1.549908)
			(stroke
				(width 0.1524)
				(type default)
			)
			(layer "F.SilkS")
		)
		(fp_line
			(start -1.050036 -0.2286)
			(end -1.050036 0.2286)
			(stroke
				(width 0.1524)
				(type default)
			)
			(layer "F.SilkS")
		)
		(fp_line
			(start -1.050036 -1.549908)
			(end -1.050036 -0.762)
			(stroke
				(width 0.1524)
				(type default)
			)
			(layer "F.SilkS")
		)
		(fp_poly
			(pts
				(xy -1.446022 -0.736854) (xy -1.913382 -0.89281) (xy -1.601724 -1.204468)
			)
			(stroke
				(width 0)
				(type default)
			)
			(fill yes)
			(layer "F.SilkS")
		)
		(fp_line
			(start 1.050036 1.549908)
			(end 1.050036 -1.549908)
			(stroke
				(width 0.1)
				(type default)
			)
			(layer "F.Fab")
		)
		(fp_line
			(start 1.050036 -1.549908)
			(end -1.050036 -1.549908)
			(stroke
				(width 0.1)
				(type default)
			)
			(layer "F.Fab")
		)
		(fp_line
			(start -1.050036 1.549908)
			(end 1.050036 1.549908)
			(stroke
				(width 0.1)
				(type default)
			)
			(layer "F.Fab")
		)
		(fp_line
			(start -1.050036 -1.549908)
			(end -1.050036 1.549908)
			(stroke
				(width 0.1)
				(type default)
			)
			(layer "F.Fab")
		)
		(fp_poly
			(pts
				(xy -1.851914 -0.720344) (xy -1.411224 -0.499872) (xy -1.851914 -0.279654)
			)
			(stroke
				(width 0)
				(type default)
			)
			(fill yes)
			(layer "F.Fab")
		)
		(pad "1" smd rect
			(at -0.54991 -0.499872 270)
			(size 0.254 1.4986)
			(layers "F.Cu" "F.Mask" "F.Paste")
			(net "SW_P1V8_PCH_AUX_FLT")
		)
		(pad "2" smd rect
			(at -0.54991 0.499872 270)
			(size 0.254 1.4986)
			(layers "F.Cu" "F.Mask" "F.Paste")
			(net "GND")
		)
		(pad "3" smd rect
			(at -0.750062 1.450086 180)
			(size 0.254 0.7112)
			(layers "F.Cu" "F.Mask" "F.Paste")
			(net "P1V8_PCH_AUX_VCC")
		)
		(pad "4" smd rect
			(at -0.249936 1.450086 180)
			(size 0.254 0.7112)
			(layers "F.Cu" "F.Mask" "F.Paste")
			(net "GND")
		)
		(pad "5" smd rect
			(at 0.249936 1.450086 180)
			(size 0.254 0.7112)
			(layers "F.Cu" "F.Mask" "F.Paste")
			(net "FM_PCH_P1V8_AUX_EN_R")
		)
		(pad "6" smd rect
			(at 0.750062 1.450086 180)
			(size 0.254 0.7112)
			(layers "F.Cu" "F.Mask" "F.Paste")
			(net "P1V8_PCH_AUX_VCC")
		)
		(pad "7" smd rect
			(at 0.94996 0.499872 270)
			(size 0.254 0.7112)
			(layers "F.Cu" "F.Mask" "F.Paste")
			(net "P1V8_PCH_AUX_MODE")
		)
		(pad "8" smd rect
			(at 0.54991 0 270)
			(size 0.254 1.4986)
			(layers "F.Cu" "F.Mask" "F.Paste")
			(net "SW_P1V8_PCH_AUX_SW")
		)
		(pad "9" smd rect
			(at 0.94996 -0.499872 270)
			(size 0.254 0.7112)
			(layers "F.Cu" "F.Mask" "F.Paste")
			(net "SW_P1V8_PCH_AUX_BST")
		)
		(pad "10" smd rect
			(at 0.750062 -1.450086 180)
			(size 0.254 0.7112)
			(layers "F.Cu" "F.Mask" "F.Paste")
			(net "P1V8_PCH_AUX_VCC")
		)
		(pad "11" smd rect
			(at 0.249936 -1.450086 180)
			(size 0.254 0.7112)
			(layers "F.Cu" "F.Mask" "F.Paste")
			(net "GND")
		)
		(pad "12" smd rect
			(at -0.249936 -1.450086 180)
			(size 0.254 0.7112)
			(layers "F.Cu" "F.Mask" "F.Paste")
			(net "P1V8_PCH_AUX")
		)
		(pad "13" smd rect
			(at -0.750062 -1.450086 180)
			(size 0.254 0.7112)
			(layers "F.Cu" "F.Mask" "F.Paste")
			(net "PWRGD_P1V8_PCH_AUX_R")
		)
	)
)
